(kicad_pcb
	(version 20260206)
	(generator "pcbnew")
	(generator_version "10.0")
	(general
		(thickness 1.6)
		(legacy_teardrops no)
	)
	(paper "A4")
	(title_block
		(title "9054_F0T_PDB_BD_GPU_F_V04_1213_1550_OCP.brd")
		(comment 1 "Grand Teton / footprints 27-33 of 608")
	)
	(layers
		(0 "F.Cu" signal "TOP")
		(4 "In1.Cu" signal "GND")
		(6 "In2.Cu" signal "IN1")
		(8 "In3.Cu" signal "GND1")
		(10 "In4.Cu" signal "VCC")
		(12 "In5.Cu" signal "VCC1")
		(14 "In6.Cu" signal "GND2")
		(16 "In7.Cu" signal "IN2")
		(18 "In8.Cu" signal "GND3")
		(2 "B.Cu" signal "BOTTOM")
		(9 "F.Adhes" user "F.Adhesive")
		(11 "B.Adhes" user "B.Adhesive")
		(13 "F.Paste" user "Package Geometry/Pastemask Top")
		(15 "B.Paste" user "Package Geometry/Pastemask Bottom")
		(5 "F.SilkS" user "Ref Des/Silkscreen Top")
		(7 "B.SilkS" user "Ref Des/Silkscreen Bottom")
		(1 "F.Mask" user "Board Geometry/Soldermask Top")
		(3 "B.Mask" user "Board Geometry/Soldermask Bottom")
		(17 "Dwgs.User" user "User.Drawings")
		(19 "Cmts.User" user "User.Comments")
		(21 "Eco1.User" user "User.Eco1")
		(23 "Eco2.User" user "User.Eco2")
		(25 "Edge.Cuts" user "Board Geometry/Outline")
		(27 "Margin" user)
		(31 "F.CrtYd" user "Package Geometry/Place Bound Top")
		(29 "B.CrtYd" user "Package Geometry/Place Bound Bottom")
		(35 "F.Fab" user "Ref Des/Assembly Top")
		(33 "B.Fab" user "Ref Des/Assembly Bottom")
	)
	(footprint ""
		(layer "F.Cu")
		(at 76.754482 -63.657226)
		(property "Reference" "ME3"
			(at 0 0 0)
			(layer "F.SilkS")
			(hide yes)
			(effects
				(font
					(size 1.27 1.27)
				)
			)
		)
		(property "Value" ""
			(at 0 0 0)
			(layer "F.Fab")
			(effects
				(font
					(size 1.27 1.27)
				)
			)
		)
		(duplicate_pad_numbers_are_jumpers no)
	)
	(footprint ""
		(layer "F.Cu")
		(at 450.342 -41.148 -90)
		(property "Reference" "R5"
			(at 0 0 270)
			(layer "F.SilkS")
			(hide yes)
			(effects
				(font
					(size 1.27 1.27)
				)
			)
		)
		(property "Value" ""
			(at 0 0 270)
			(layer "F.Fab")
			(effects
				(font
					(size 1.27 1.27)
				)
			)
		)
		(duplicate_pad_numbers_are_jumpers no)
		(fp_line
			(start -0.7874 0.4064)
			(end -0.7874 -0.4064)
			(stroke
				(width 0.1524)
				(type default)
			)
			(layer "F.SilkS")
		)
		(fp_line
			(start 0.7874 0.4064)
			(end -0.7874 0.4064)
			(stroke
				(width 0.1524)
				(type default)
			)
			(layer "F.SilkS")
		)
		(fp_line
			(start -0.7874 -0.4064)
			(end 0.7874 -0.4064)
			(stroke
				(width 0.1524)
				(type default)
			)
			(layer "F.SilkS")
		)
		(fp_line
			(start 0.7874 -0.4064)
			(end 0.7874 0.4064)
			(stroke
				(width 0.1524)
				(type default)
			)
			(layer "F.SilkS")
		)
		(fp_line
			(start -0.67945 0.3048)
			(end -0.67945 -0.305054)
			(stroke
				(width 0.1)
				(type default)
			)
			(layer "F.Fab")
		)
		(fp_line
			(start -0.12065 0.3048)
			(end -0.67945 0.3048)
			(stroke
				(width 0.1)
				(type default)
			)
			(layer "F.Fab")
		)
		(fp_line
			(start 0.120396 0.3048)
			(end 0.120396 0.2794)
			(stroke
				(width 0.1)
				(type default)
			)
			(layer "F.Fab")
		)
		(fp_line
			(start 0.67945 0.3048)
			(end 0.120396 0.3048)
			(stroke
				(width 0.1)
				(type default)
			)
			(layer "F.Fab")
		)
		(fp_line
			(start -0.12065 0.2794)
			(end -0.12065 0.3048)
			(stroke
				(width 0.1)
				(type default)
			)
			(layer "F.Fab")
		)
		(fp_line
			(start 0.120396 0.2794)
			(end -0.12065 0.2794)
			(stroke
				(width 0.1)
				(type default)
			)
			(layer "F.Fab")
		)
		(fp_line
			(start -0.12065 -0.2794)
			(end 0.12065 -0.2794)
			(stroke
				(width 0.1)
				(type default)
			)
			(layer "F.Fab")
		)
		(fp_line
			(start 0.12065 -0.2794)
			(end 0.12065 -0.3048)
			(stroke
				(width 0.1)
				(type default)
			)
			(layer "F.Fab")
		)
		(fp_line
			(start 0.12065 -0.3048)
			(end 0.67945 -0.3048)
			(stroke
				(width 0.1)
				(type default)
			)
			(layer "F.Fab")
		)
		(fp_line
			(start 0.67945 -0.3048)
			(end 0.67945 0.3048)
			(stroke
				(width 0.1)
				(type default)
			)
			(layer "F.Fab")
		)
		(fp_line
			(start -0.67945 -0.305054)
			(end -0.12065 -0.305054)
			(stroke
				(width 0.1)
				(type default)
			)
			(layer "F.Fab")
		)
		(fp_line
			(start -0.12065 -0.305054)
			(end -0.12065 -0.2794)
			(stroke
				(width 0.1)
				(type default)
			)
			(layer "F.Fab")
		)
		(pad "1" smd circle
			(at -0.40005 0 270)
			(size 0 0)
			(layers "F.Cu" "F.Mask" "F.Paste")
			(net "SMB_PDB_MISC_SDA_R")
		)
		(pad "2" smd circle
			(at 0.40005 0 270)
			(size 0 0)
			(layers "F.Cu" "F.Mask" "F.Paste")
			(net "SMB_PDB_MISC_SDA")
		)
	)
	(footprint ""
		(layer "F.Cu")
		(at 172.466 -81.153)
		(property "Reference" "U35"
			(at 0.9525 -2.24663 0)
			(unlocked yes)
			(layer "F.SilkS")
			(effects
				(font
					(size 0.7874 0.5842)
					(thickness 0.1524)
				)
				(justify left)
			)
		)
		(property "Value" ""
			(at 0 0 0)
			(layer "F.Fab")
			(effects
				(font
					(size 1.27 1.27)
				)
			)
		)
		(duplicate_pad_numbers_are_jumpers no)
		(fp_line
			(start -1.733296 -1.549908)
			(end -1.733296 1.549908)
			(stroke
				(width 0.1524)
				(type default)
			)
			(layer "F.SilkS")
		)
		(fp_line
			(start -1.733296 1.549908)
			(end 1.733296 1.549908)
			(stroke
				(width 0.1524)
				(type default)
			)
			(layer "F.SilkS")
		)
		(fp_line
			(start -0.660908 -1.549908)
			(end -1.733296 -1.549908)
			(stroke
				(width 0.1524)
				(type default)
			)
			(layer "F.SilkS")
		)
		(fp_line
			(start 0 -0.889)
			(end -0.660908 -1.549908)
			(stroke
				(width 0.1524)
				(type default)
			)
			(layer "F.SilkS")
		)
		(fp_line
			(start 0.660908 -1.549908)
			(end 0 -0.889)
			(stroke
				(width 0.1524)
				(type default)
			)
			(layer "F.SilkS")
		)
		(fp_line
			(start 1.733296 -1.549908)
			(end 0.660908 -1.549908)
			(stroke
				(width 0.1524)
				(type default)
			)
			(layer "F.SilkS")
		)
		(fp_line
			(start 1.733296 1.549908)
			(end 1.733296 -1.549908)
			(stroke
				(width 0.1524)
				(type default)
			)
			(layer "F.SilkS")
		)
		(fp_poly
			(pts
				(xy -2.159 -1.883156) (xy -2.518156 -1.524) (xy -1.979422 -1.344422)
			)
			(stroke
				(width 0)
				(type default)
			)
			(fill yes)
			(layer "F.SilkS")
		)
		(fp_line
			(start -0.849884 -1.549908)
			(end -0.849884 1.549908)
			(stroke
				(width 0.1)
				(type default)
			)
			(layer "F.Fab")
		)
		(fp_line
			(start -0.849884 1.549908)
			(end 0.849884 1.549908)
			(stroke
				(width 0.1)
				(type default)
			)
			(layer "F.Fab")
		)
		(fp_line
			(start 0.849884 -1.549908)
			(end -0.849884 -1.549908)
			(stroke
				(width 0.1)
				(type default)
			)
			(layer "F.Fab")
		)
		(fp_line
			(start 0.849884 1.549908)
			(end 0.849884 -1.549908)
			(stroke
				(width 0.1)
				(type default)
			)
			(layer "F.Fab")
		)
		(fp_poly
			(pts
				(xy -2.4384 -1.20396) (xy -2.4384 -0.69596) (xy -1.9304 -0.94996)
			)
			(stroke
				(width 0)
				(type default)
			)
			(fill yes)
			(layer "F.Fab")
		)
		(pad "1" smd rect
			(at -1.199896 -0.94996 270)
			(size 0.5588 0.8128)
			(layers "F.Cu" "F.Mask" "F.Paste")
			(net "FM_HS2_EN_BUSBAR")
		)
		(pad "2" smd rect
			(at -1.199896 0 270)
			(size 0.5588 0.8128)
			(layers "F.Cu" "F.Mask" "F.Paste")
			(net "FM_HS2_EN_FUSE")
		)
		(pad "3" smd rect
			(at -1.199896 0.94996 270)
			(size 0.5588 0.8128)
			(layers "F.Cu" "F.Mask" "F.Paste")
			(net "GND")
		)
		(pad "4" smd rect
			(at 1.199896 0.94996 270)
			(size 0.5588 0.8128)
			(layers "F.Cu" "F.Mask" "F.Paste")
			(net "P52V_HS2_EN")
		)
		(pad "5" smd rect
			(at 1.199896 -0.94996 270)
			(size 0.5588 0.8128)
			(layers "F.Cu" "F.Mask" "F.Paste")
			(net "P3V3_2_AND")
		)
	)
	(footprint ""
		(layer "F.Cu")
		(at 275.3614 -63.881 180)
		(property "Reference" "R357"
			(at 0 0 180)
			(layer "F.SilkS")
			(hide yes)
			(effects
				(font
					(size 1.27 1.27)
				)
			)
		)
		(property "Value" ""
			(at 0 0 180)
			(layer "F.Fab")
			(effects
				(font
					(size 1.27 1.27)
				)
			)
		)
		(duplicate_pad_numbers_are_jumpers no)
		(fp_line
			(start 0.7874 0.4064)
			(end -0.7874 0.4064)
			(stroke
				(width 0.1524)
				(type default)
			)
			(layer "F.SilkS")
		)
		(fp_line
			(start 0.7874 -0.4064)
			(end 0.7874 0.4064)
			(stroke
				(width 0.1524)
				(type default)
			)
			(layer "F.SilkS")
		)
		(fp_line
			(start -0.7874 0.4064)
			(end -0.7874 -0.4064)
			(stroke
				(width 0.1524)
				(type default)
			)
			(layer "F.SilkS")
		)
		(fp_line
			(start -0.7874 -0.4064)
			(end 0.7874 -0.4064)
			(stroke
				(width 0.1524)
				(type default)
			)
			(layer "F.SilkS")
		)
		(fp_line
			(start 0.67945 0.3048)
			(end 0.120396 0.3048)
			(stroke
				(width 0.1)
				(type default)
			)
			(layer "F.Fab")
		)
		(fp_line
			(start 0.67945 -0.3048)
			(end 0.67945 0.3048)
			(stroke
				(width 0.1)
				(type default)
			)
			(layer "F.Fab")
		)
		(fp_line
			(start 0.12065 -0.2794)
			(end 0.12065 -0.3048)
			(stroke
				(width 0.1)
				(type default)
			)
			(layer "F.Fab")
		)
		(fp_line
			(start 0.12065 -0.3048)
			(end 0.67945 -0.3048)
			(stroke
				(width 0.1)
				(type default)
			)
			(layer "F.Fab")
		)
		(fp_line
			(start 0.120396 0.3048)
			(end 0.120396 0.2794)
			(stroke
				(width 0.1)
				(type default)
			)
			(layer "F.Fab")
		)
		(fp_line
			(start 0.120396 0.2794)
			(end -0.12065 0.2794)
			(stroke
				(width 0.1)
				(type default)
			)
			(layer "F.Fab")
		)
		(fp_line
			(start -0.12065 0.3048)
			(end -0.67945 0.3048)
			(stroke
				(width 0.1)
				(type default)
			)
			(layer "F.Fab")
		)
		(fp_line
			(start -0.12065 0.2794)
			(end -0.12065 0.3048)
			(stroke
				(width 0.1)
				(type default)
			)
			(layer "F.Fab")
		)
		(fp_line
			(start -0.12065 -0.2794)
			(end 0.12065 -0.2794)
			(stroke
				(width 0.1)
				(type default)
			)
			(layer "F.Fab")
		)
		(fp_line
			(start -0.12065 -0.305054)
			(end -0.12065 -0.2794)
			(stroke
				(width 0.1)
				(type default)
			)
			(layer "F.Fab")
		)
		(fp_line
			(start -0.67945 0.3048)
			(end -0.67945 -0.305054)
			(stroke
				(width 0.1)
				(type default)
			)
			(layer "F.Fab")
		)
		(fp_line
			(start -0.67945 -0.305054)
			(end -0.12065 -0.305054)
			(stroke
				(width 0.1)
				(type default)
			)
			(layer "F.Fab")
		)
		(pad "1" smd circle
			(at -0.40005 0 180)
			(size 0 0)
			(layers "F.Cu" "F.Mask" "F.Paste")
			(net "P3V3_AUX")
		)
		(pad "2" smd circle
			(at 0.40005 0 180)
			(size 0 0)
			(layers "F.Cu" "F.Mask" "F.Paste")
			(net "P52V_HS1_GPO1")
		)
	)
	(footprint ""
		(layer "F.Cu")
		(at 140.79982 -71.755 180)
		(property "Reference" "PR6982"
			(at 0 0 180)
			(layer "F.SilkS")
			(hide yes)
			(effects
				(font
					(size 1.27 1.27)
				)
			)
		)
		(property "Value" ""
			(at 0 0 180)
			(layer "F.Fab")
			(effects
				(font
					(size 1.27 1.27)
				)
			)
		)
		(duplicate_pad_numbers_are_jumpers no)
		(fp_line
			(start 1.2954 0.5842)
			(end -1.2954 0.5842)
			(stroke
				(width 0.1524)
				(type default)
			)
			(layer "F.SilkS")
		)
		(fp_line
			(start 1.2954 -0.5842)
			(end 1.2954 0.5842)
			(stroke
				(width 0.1524)
				(type default)
			)
			(layer "F.SilkS")
		)
		(fp_line
			(start -1.2954 0.5842)
			(end -1.2954 -0.5842)
			(stroke
				(width 0.1524)
				(type default)
			)
			(layer "F.SilkS")
		)
		(fp_line
			(start -1.2954 -0.5842)
			(end 1.2954 -0.5842)
			(stroke
				(width 0.1524)
				(type default)
			)
			(layer "F.SilkS")
		)
		(fp_line
			(start 1.1938 0.4064)
			(end 0.8636 0.4064)
			(stroke
				(width 0.1)
				(type default)
			)
			(layer "F.Fab")
		)
		(fp_line
			(start 1.1938 -0.406654)
			(end 1.1938 0.4064)
			(stroke
				(width 0.1)
				(type default)
			)
			(layer "F.Fab")
		)
		(fp_line
			(start 0.8636 0.4572)
			(end -0.8636 0.4572)
			(stroke
				(width 0.1)
				(type default)
			)
			(layer "F.Fab")
		)
		(fp_line
			(start 0.8636 0.4064)
			(end 0.8636 0.4572)
			(stroke
				(width 0.1)
				(type default)
			)
			(layer "F.Fab")
		)
		(fp_line
			(start 0.8636 -0.406654)
			(end 1.1938 -0.406654)
			(stroke
				(width 0.1)
				(type default)
			)
			(layer "F.Fab")
		)
		(fp_line
			(start 0.8636 -0.4572)
			(end 0.8636 -0.406654)
			(stroke
				(width 0.1)
				(type default)
			)
			(layer "F.Fab")
		)
		(fp_line
			(start -0.8636 0.4572)
			(end -0.8636 0.4318)
			(stroke
				(width 0.1)
				(type default)
			)
			(layer "F.Fab")
		)
		(fp_line
			(start -0.8636 0.4318)
			(end -0.8636 0.4064)
			(stroke
				(width 0.1)
				(type default)
			)
			(layer "F.Fab")
		)
		(fp_line
			(start -0.8636 0.4064)
			(end -1.1938 0.4064)
			(stroke
				(width 0.1)
				(type default)
			)
			(layer "F.Fab")
		)
		(fp_line
			(start -0.8636 -0.406654)
			(end -0.8636 -0.4572)
			(stroke
				(width 0.1)
				(type default)
			)
			(layer "F.Fab")
		)
		(fp_line
			(start -0.8636 -0.4572)
			(end 0.8636 -0.4572)
			(stroke
				(width 0.1)
				(type default)
			)
			(layer "F.Fab")
		)
		(fp_line
			(start -1.1938 0.4064)
			(end -1.1938 -0.406654)
			(stroke
				(width 0.1)
				(type default)
			)
			(layer "F.Fab")
		)
		(fp_line
			(start -1.1938 -0.406654)
			(end -0.8636 -0.406654)
			(stroke
				(width 0.1)
				(type default)
			)
			(layer "F.Fab")
		)
		(pad "1" smd rect
			(at -0.7366 0 90)
			(size 0.7112 0.8128)
			(layers "F.Cu" "F.Mask" "F.Paste")
			(net "P52V_HS2_4287_S1N")
		)
		(pad "2" smd rect
			(at 0.7366 0 90)
			(size 0.7112 0.8128)
			(layers "F.Cu" "F.Mask" "F.Paste")
			(net "P52V_HS2_SENSE_N_R1")
		)
	)
	(footprint ""
		(layer "F.Cu")
		(at 33.72739 -30.607)
		(property "Reference" "D2"
			(at -0.93599 1.29667 0)
			(unlocked yes)
			(layer "F.SilkS")
			(effects
				(font
					(size 0.7874 0.5842)
					(thickness 0.1524)
				)
				(justify left)
			)
		)
		(property "Value" ""
			(at 0 0 0)
			(layer "F.Fab")
			(effects
				(font
					(size 1.27 1.27)
				)
			)
		)
		(duplicate_pad_numbers_are_jumpers no)
		(fp_line
			(start -0.90678 0.4826)
			(end -0.90678 -0.4699)
			(stroke
				(width 0.1524)
				(type default)
			)
			(layer "F.SilkS")
		)
		(fp_line
			(start -0.89408 -0.4826)
			(end 0.90678 -0.4826)
			(stroke
				(width 0.1524)
				(type default)
			)
			(layer "F.SilkS")
		)
		(fp_line
			(start -0.79248 -0.4826)
			(end 1.03378 -0.4826)
			(stroke
				(width 0.1524)
				(type default)
			)
			(layer "F.SilkS")
		)
		(fp_line
			(start -0.64008 -0.4826)
			(end 1.16078 -0.4826)
			(stroke
				(width 0.1524)
				(type default)
			)
			(layer "F.SilkS")
		)
		(fp_line
			(start 0.90678 -0.4826)
			(end 0.90678 0.4826)
			(stroke
				(width 0.1524)
				(type default)
			)
			(layer "F.SilkS")
		)
		(fp_line
			(start 0.90678 0.4826)
			(end -0.90678 0.4826)
			(stroke
				(width 0.1524)
				(type default)
			)
			(layer "F.SilkS")
		)
		(fp_line
			(start 1.03378 -0.4826)
			(end 1.03378 0.4826)
			(stroke
				(width 0.1524)
				(type default)
			)
			(layer "F.SilkS")
		)
		(fp_line
			(start 1.03378 0.4826)
			(end -0.79248 0.4826)
			(stroke
				(width 0.1524)
				(type default)
			)
			(layer "F.SilkS")
		)
		(fp_line
			(start 1.16078 -0.4826)
			(end 1.16078 0.4826)
			(stroke
				(width 0.1524)
				(type default)
			)
			(layer "F.SilkS")
		)
		(fp_line
			(start 1.16078 0.4826)
			(end -0.64008 0.4826)
			(stroke
				(width 0.1524)
				(type default)
			)
			(layer "F.SilkS")
		)
		(fp_line
			(start -0.499872 -0.249936)
			(end 0.499872 -0.249936)
			(stroke
				(width 0.1)
				(type default)
			)
			(layer "F.Fab")
		)
		(fp_line
			(start -0.499872 0.249936)
			(end -0.499872 -0.249936)
			(stroke
				(width 0.1)
				(type default)
			)
			(layer "F.Fab")
		)
		(fp_line
			(start 0.499872 -0.249936)
			(end 0.499872 0.249936)
			(stroke
				(width 0.1)
				(type default)
			)
			(layer "F.Fab")
		)
		(fp_line
			(start 0.499872 0.249936)
			(end -0.499872 0.249936)
			(stroke
				(width 0.1)
				(type default)
			)
			(layer "F.Fab")
		)
		(pad "A" smd rect
			(at -0.47498 0)
			(size 0.6096 0.7112)
			(layers "F.Cu" "F.Mask" "F.Paste")
			(net "LED_D2_R5")
		)
		(pad "C" smd rect
			(at 0.47498 0)
			(size 0.6096 0.7112)
			(layers "F.Cu" "F.Mask" "F.Paste")
			(net "GND")
		)
	)
	(footprint ""
		(layer "F.Cu")
		(at 145.11782 -37.9222)
		(property "Reference" "PR6992"
			(at 0 0 0)
			(layer "F.SilkS")
			(hide yes)
			(effects
				(font
					(size 1.27 1.27)
				)
			)
		)
		(property "Value" ""
			(at 0 0 0)
			(layer "F.Fab")
			(effects
				(font
					(size 1.27 1.27)
				)
			)
		)
		(duplicate_pad_numbers_are_jumpers no)
		(fp_line
			(start -1.2954 -0.5842)
			(end 1.2954 -0.5842)
			(stroke
				(width 0.1524)
				(type default)
			)
			(layer "F.SilkS")
		)
		(fp_line
			(start -1.2954 0.5842)
			(end -1.2954 -0.5842)
			(stroke
				(width 0.1524)
				(type default)
			)
			(layer "F.SilkS")
		)
		(fp_line
			(start 1.2954 -0.5842)
			(end 1.2954 0.5842)
			(stroke
				(width 0.1524)
				(type default)
			)
			(layer "F.SilkS")
		)
		(fp_line
			(start 1.2954 0.5842)
			(end -1.2954 0.5842)
			(stroke
				(width 0.1524)
				(type default)
			)
			(layer "F.SilkS")
		)
		(fp_line
			(start -1.1938 -0.406654)
			(end -0.8636 -0.406654)
			(stroke
				(width 0.1)
				(type default)
			)
			(layer "F.Fab")
		)
		(fp_line
			(start -1.1938 0.4064)
			(end -1.1938 -0.406654)
			(stroke
				(width 0.1)
				(type default)
			)
			(layer "F.Fab")
		)
		(fp_line
			(start -0.8636 -0.4572)
			(end 0.8636 -0.4572)
			(stroke
				(width 0.1)
				(type default)
			)
			(layer "F.Fab")
		)
		(fp_line
			(start -0.8636 -0.406654)
			(end -0.8636 -0.4572)
			(stroke
				(width 0.1)
				(type default)
			)
			(layer "F.Fab")
		)
		(fp_line
			(start -0.8636 0.4064)
			(end -1.1938 0.4064)
			(stroke
				(width 0.1)
				(type default)
			)
			(layer "F.Fab")
		)
		(fp_line
			(start -0.8636 0.4318)
			(end -0.8636 0.4064)
			(stroke
				(width 0.1)
				(type default)
			)
			(layer "F.Fab")
		)
		(fp_line
			(start -0.8636 0.4572)
			(end -0.8636 0.4318)
			(stroke
				(width 0.1)
				(type default)
			)
			(layer "F.Fab")
		)
		(fp_line
			(start 0.8636 -0.4572)
			(end 0.8636 -0.406654)
			(stroke
				(width 0.1)
				(type default)
			)
			(layer "F.Fab")
		)
		(fp_line
			(start 0.8636 -0.406654)
			(end 1.1938 -0.406654)
			(stroke
				(width 0.1)
				(type default)
			)
			(layer "F.Fab")
		)
		(fp_line
			(start 0.8636 0.4064)
			(end 0.8636 0.4572)
			(stroke
				(width 0.1)
				(type default)
			)
			(layer "F.Fab")
		)
		(fp_line
			(start 0.8636 0.4572)
			(end -0.8636 0.4572)
			(stroke
				(width 0.1)
				(type default)
			)
			(layer "F.Fab")
		)
		(fp_line
			(start 1.1938 -0.406654)
			(end 1.1938 0.4064)
			(stroke
				(width 0.1)
				(type default)
			)
			(layer "F.Fab")
		)
		(fp_line
			(start 1.1938 0.4064)
			(end 0.8636 0.4064)
			(stroke
				(width 0.1)
				(type default)
			)
			(layer "F.Fab")
		)
		(pad "1" smd rect
			(at -0.7366 0 270)
			(size 0.7112 0.8128)
			(layers "F.Cu" "F.Mask" "F.Paste")
			(net "P52V_HS2_4287_S2P")
		)
		(pad "2" smd rect
			(at 0.7366 0 270)
			(size 0.7112 0.8128)
			(layers "F.Cu" "F.Mask" "F.Paste")
			(net "P52V_HS2_SENSE_P_R2")
		)
	)
)
